# S9S_MB_2U (Grand Teton) — schematic netlist excerpt (pin names and nets, part order shuffled) for the footprints in the layout excerpt that follows; sources: Cadence DE-HDL packaged netlist, KiCad conversion of 03242023_DA0F0TMBIJ0_F0T_Motherboard_J_brd_V01_OCP.brd

PC456_P1_2  Q_CAP  22UF 4V 20% X6S  pkg C0805  page 293 : A = PVCCINFAON_CPU1 ; B = GND
PR372  Q_RES  1K 1% CHIP  pkg 0402LF  page 278 : A = P3V3_AUX ; B = PVCCD_HV_CPU0_FAULT
C1205  Q_CAP  10UF 6.3V 20% X6S  pkg C0402  page 189 : A = P1V05_PCH_AUX ; B = GND

(kicad_pcb
	(version 20260206)
	(generator "pcbnew")
	(generator_version "10.0")
	(general
		(thickness 1.6)
		(legacy_teardrops no)
	)
	(paper "A4")
	(title_block
		(title "03242023_DA0F0TMBIJ0_F0T_Motherboard_J_brd_V01_OCP.brd")
		(comment 1 "Grand Teton / footprints 5770-5772 of 6105")
	)
	(layers
		(0 "F.Cu" signal "TOP")
		(4 "In1.Cu" signal "GND")
		(6 "In2.Cu" signal "IN1")
		(8 "In3.Cu" signal "GND1")
		(10 "In4.Cu" signal "IN2")
		(12 "In5.Cu" signal "GND2")
		(14 "In6.Cu" signal "IN3")
		(16 "In7.Cu" signal "GND3")
		(18 "In8.Cu" signal "VCC")
		(20 "In9.Cu" signal "VCC1")
		(22 "In10.Cu" signal "GND4")
		(24 "In11.Cu" signal "IN4")
		(26 "In12.Cu" signal "GND5")
		(28 "In13.Cu" signal "IN5")
		(30 "In14.Cu" signal "GND6")
		(32 "In15.Cu" signal "IN6")
		(34 "In16.Cu" signal "GND7")
		(2 "B.Cu" signal "BOTTOM")
		(9 "F.Adhes" user "F.Adhesive")
		(11 "B.Adhes" user "B.Adhesive")
		(13 "F.Paste" user "Package Geometry/Pastemask Top")
		(15 "B.Paste" user "Package Geometry/Pastemask Bottom")
		(5 "F.SilkS" user "Ref Des/Silkscreen Top")
		(7 "B.SilkS" user "Ref Des/Silkscreen Bottom")
		(1 "F.Mask" user "Board Geometry/Soldermask Top")
		(3 "B.Mask" user "Board Geometry/Soldermask Bottom")
		(17 "Dwgs.User" user "User.Drawings")
		(19 "Cmts.User" user "User.Comments")
		(21 "Eco1.User" user "User.Eco1")
		(23 "Eco2.User" user "User.Eco2")
		(25 "Edge.Cuts" user "Board Geometry/Outline")
		(27 "Margin" user)
		(31 "F.CrtYd" user "Package Geometry/Place Bound Top")
		(29 "B.CrtYd" user "Package Geometry/Place Bound Bottom")
		(35 "F.Fab" user "Ref Des/Assembly Top")
		(33 "B.Fab" user "Ref Des/Assembly Bottom")
	)
	(footprint ""
		(layer "B.Cu")
		(at 339.244686 -46.499272 180)
		(property "Reference" "C1205"
			(at 0 0 0)
			(layer "B.SilkS")
			(hide yes)
			(effects
				(font
					(size 1.27 1.27)
				)
				(justify mirror)
			)
		)
		(property "Value" ""
			(at 0 0 0)
			(layer "B.Fab")
			(effects
				(font
					(size 1.27 1.27)
				)
				(justify mirror)
			)
		)
		(duplicate_pad_numbers_are_jumpers no)
		(fp_line
			(start 0.7874 0.4064)
			(end 0.7874 -0.4064)
			(stroke
				(width 0.1524)
				(type default)
			)
			(layer "B.SilkS")
		)
		(fp_line
			(start 0.7874 -0.4064)
			(end -0.7874 -0.4064)
			(stroke
				(width 0.1524)
				(type default)
			)
			(layer "B.SilkS")
		)
		(fp_line
			(start -0.7874 0.4064)
			(end 0.7874 0.4064)
			(stroke
				(width 0.1524)
				(type default)
			)
			(layer "B.SilkS")
		)
		(fp_line
			(start -0.7874 -0.4064)
			(end -0.7874 0.4064)
			(stroke
				(width 0.1524)
				(type default)
			)
			(layer "B.SilkS")
		)
		(fp_line
			(start 0.67945 0.3048)
			(end 0.67945 -0.305054)
			(stroke
				(width 0.1)
				(type default)
			)
			(layer "B.Fab")
		)
		(fp_line
			(start 0.67945 -0.305054)
			(end 0.12065 -0.305054)
			(stroke
				(width 0.1)
				(type default)
			)
			(layer "B.Fab")
		)
		(fp_line
			(start 0.12065 0.3048)
			(end 0.67945 0.3048)
			(stroke
				(width 0.1)
				(type default)
			)
			(layer "B.Fab")
		)
		(fp_line
			(start 0.12065 0.2794)
			(end 0.12065 0.3048)
			(stroke
				(width 0.1)
				(type default)
			)
			(layer "B.Fab")
		)
		(fp_line
			(start 0.12065 -0.2794)
			(end -0.12065 -0.2794)
			(stroke
				(width 0.1)
				(type default)
			)
			(layer "B.Fab")
		)
		(fp_line
			(start 0.12065 -0.305054)
			(end 0.12065 -0.2794)
			(stroke
				(width 0.1)
				(type default)
			)
			(layer "B.Fab")
		)
		(fp_line
			(start -0.120396 0.3048)
			(end -0.120396 0.2794)
			(stroke
				(width 0.1)
				(type default)
			)
			(layer "B.Fab")
		)
		(fp_line
			(start -0.120396 0.2794)
			(end 0.12065 0.2794)
			(stroke
				(width 0.1)
				(type default)
			)
			(layer "B.Fab")
		)
		(fp_line
			(start -0.12065 -0.2794)
			(end -0.12065 -0.3048)
			(stroke
				(width 0.1)
				(type default)
			)
			(layer "B.Fab")
		)
		(fp_line
			(start -0.12065 -0.3048)
			(end -0.67945 -0.3048)
			(stroke
				(width 0.1)
				(type default)
			)
			(layer "B.Fab")
		)
		(fp_line
			(start -0.67945 0.3048)
			(end -0.120396 0.3048)
			(stroke
				(width 0.1)
				(type default)
			)
			(layer "B.Fab")
		)
		(fp_line
			(start -0.67945 -0.3048)
			(end -0.67945 0.3048)
			(stroke
				(width 0.1)
				(type default)
			)
			(layer "B.Fab")
		)
		(pad "1" smd circle
			(at 0.40005 0)
			(size 0 0)
			(layers "B.Cu" "B.Mask" "B.Paste")
			(net "P1V05_PCH_AUX")
		)
		(pad "2" smd circle
			(at -0.40005 0)
			(size 0 0)
			(layers "B.Cu" "B.Mask" "B.Paste")
			(net "GND")
		)
	)
	(footprint ""
		(layer "B.Cu")
		(at 62.996572 -144.44726)
		(property "Reference" "PC456_P1_2"
			(at 0 0 0)
			(layer "B.SilkS")
			(hide yes)
			(effects
				(font
					(size 1.27 1.27)
				)
				(justify mirror)
			)
		)
		(property "Value" ""
			(at 0 0 0)
			(layer "B.Fab")
			(effects
				(font
					(size 1.27 1.27)
				)
				(justify mirror)
			)
		)
		(duplicate_pad_numbers_are_jumpers no)
		(fp_line
			(start -1.524 -0.762)
			(end -1.524 0.762)
			(stroke
				(width 0.1524)
				(type default)
			)
			(layer "B.SilkS")
		)
		(fp_line
			(start -1.524 0.762)
			(end 1.524 0.762)
			(stroke
				(width 0.1524)
				(type default)
			)
			(layer "B.SilkS")
		)
		(fp_line
			(start 1.524 -0.762)
			(end -1.524 -0.762)
			(stroke
				(width 0.1524)
				(type default)
			)
			(layer "B.SilkS")
		)
		(fp_line
			(start 1.524 0.762)
			(end 1.524 -0.762)
			(stroke
				(width 0.1524)
				(type default)
			)
			(layer "B.SilkS")
		)
		(fp_line
			(start -1.1049 -0.724916)
			(end 1.1049 -0.724916)
			(stroke
				(width 0.1)
				(type default)
			)
			(layer "B.Fab")
		)
		(fp_line
			(start -1.1049 0.724916)
			(end -1.1049 -0.724916)
			(stroke
				(width 0.1)
				(type default)
			)
			(layer "B.Fab")
		)
		(fp_line
			(start 1.1049 -0.724916)
			(end 1.1049 0.724916)
			(stroke
				(width 0.1)
				(type default)
			)
			(layer "B.Fab")
		)
		(fp_line
			(start 1.1049 0.724916)
			(end -1.1049 0.724916)
			(stroke
				(width 0.1)
				(type default)
			)
			(layer "B.Fab")
		)
		(pad "1" smd rect
			(at 0.889 0)
			(size 1.016 1.27)
			(layers "B.Cu" "B.Mask" "B.Paste")
			(net "PVCCINFAON_CPU1")
		)
		(pad "2" smd rect
			(at -0.889 0)
			(size 1.016 1.27)
			(layers "B.Cu" "B.Mask" "B.Paste")
			(net "GND")
		)
	)
	(footprint ""
		(layer "B.Cu")
		(at 428.413926 -127.578866)
		(property "Reference" "PR372"
			(at 0 0 0)
			(layer "B.SilkS")
			(hide yes)
			(effects
				(font
					(size 1.27 1.27)
				)
				(justify mirror)
			)
		)
		(property "Value" ""
			(at 0 0 0)
			(layer "B.Fab")
			(effects
				(font
					(size 1.27 1.27)
				)
				(justify mirror)
			)
		)
		(duplicate_pad_numbers_are_jumpers no)
		(fp_line
			(start -0.7874 -0.4064)
			(end -0.7874 0.4064)
			(stroke
				(width 0.1524)
				(type default)
			)
			(layer "B.SilkS")
		)
		(fp_line
			(start -0.7874 0.4064)
			(end 0.7874 0.4064)
			(stroke
				(width 0.1524)
				(type default)
			)
			(layer "B.SilkS")
		)
		(fp_line
			(start 0.7874 -0.4064)
			(end -0.7874 -0.4064)
			(stroke
				(width 0.1524)
				(type default)
			)
			(layer "B.SilkS")
		)
		(fp_line
			(start 0.7874 0.4064)
			(end 0.7874 -0.4064)
			(stroke
				(width 0.1524)
				(type default)
			)
			(layer "B.SilkS")
		)
		(fp_line
			(start -0.67945 -0.3048)
			(end -0.67945 0.3048)
			(stroke
				(width 0.1)
				(type default)
			)
			(layer "B.Fab")
		)
		(fp_line
			(start -0.67945 0.3048)
			(end -0.120396 0.3048)
			(stroke
				(width 0.1)
				(type default)
			)
			(layer "B.Fab")
		)
		(fp_line
			(start -0.12065 -0.3048)
			(end -0.67945 -0.3048)
			(stroke
				(width 0.1)
				(type default)
			)
			(layer "B.Fab")
		)
		(fp_line
			(start -0.12065 -0.2794)
			(end -0.12065 -0.3048)
			(stroke
				(width 0.1)
				(type default)
			)
			(layer "B.Fab")
		)
		(fp_line
			(start -0.120396 0.2794)
			(end 0.12065 0.2794)
			(stroke
				(width 0.1)
				(type default)
			)
			(layer "B.Fab")
		)
		(fp_line
			(start -0.120396 0.3048)
			(end -0.120396 0.2794)
			(stroke
				(width 0.1)
				(type default)
			)
			(layer "B.Fab")
		)
		(fp_line
			(start 0.12065 -0.305054)
			(end 0.12065 -0.2794)
			(stroke
				(width 0.1)
				(type default)
			)
			(layer "B.Fab")
		)
		(fp_line
			(start 0.12065 -0.2794)
			(end -0.12065 -0.2794)
			(stroke
				(width 0.1)
				(type default)
			)
			(layer "B.Fab")
		)
		(fp_line
			(start 0.12065 0.2794)
			(end 0.12065 0.3048)
			(stroke
				(width 0.1)
				(type default)
			)
			(layer "B.Fab")
		)
		(fp_line
			(start 0.12065 0.3048)
			(end 0.67945 0.3048)
			(stroke
				(width 0.1)
				(type default)
			)
			(layer "B.Fab")
		)
		(fp_line
			(start 0.67945 -0.305054)
			(end 0.12065 -0.305054)
			(stroke
				(width 0.1)
				(type default)
			)
			(layer "B.Fab")
		)
		(fp_line
			(start 0.67945 0.3048)
			(end 0.67945 -0.305054)
			(stroke
				(width 0.1)
				(type default)
			)
			(layer "B.Fab")
		)
		(pad "1" smd circle
			(at 0.40005 0 180)
			(size 0 0)
			(layers "B.Cu" "B.Mask" "B.Paste")
			(net "P3V3_AUX")
		)
		(pad "2" smd circle
			(at -0.40005 0 180)
			(size 0 0)
			(layers "B.Cu" "B.Mask" "B.Paste")
			(net "PVCCD_HV_CPU0_FAULT")
		)
	)
)
